(kicad_pcb
	(version 20260206)
	(generator "pcbnew")
	(generator_version "10.0")
	(general
		(thickness 1.6)
		(legacy_teardrops no)
	)
	(paper "A4")
	(title_block
		(title "baseboard — 13948-1b.1110WZS1818.brd")
		(comment 1 "Honey Badger (Wiwynn) / footprints 866-873 of 2523")
	)
	(layers
		(0 "F.Cu" signal "TOP")
		(4 "In1.Cu" signal "L2GND")
		(6 "In2.Cu" signal "L3")
		(8 "In3.Cu" signal "L4VCC")
		(10 "In4.Cu" signal "L5VCC")
		(12 "In5.Cu" signal "L6")
		(14 "In6.Cu" signal "L7GND")
		(2 "B.Cu" signal "BOTTOM")
		(9 "F.Adhes" user "F.Adhesive")
		(11 "B.Adhes" user "B.Adhesive")
		(13 "F.Paste" user "Package Geometry/Pastemask Top")
		(15 "B.Paste" user "Package Geometry/Pastemask Bottom")
		(5 "F.SilkS" user "Ref Des/Silkscreen Top")
		(7 "B.SilkS" user "Ref Des/Silkscreen Bottom")
		(1 "F.Mask" user "Board Geometry/Soldermask Top")
		(3 "B.Mask" user "Board Geometry/Soldermask Bottom")
		(17 "Dwgs.User" user "User.Drawings")
		(19 "Cmts.User" user "User.Comments")
		(21 "Eco1.User" user "User.Eco1")
		(23 "Eco2.User" user "User.Eco2")
		(25 "Edge.Cuts" user "Board Geometry/Outline")
		(27 "Margin" user)
		(31 "F.CrtYd" user "Package Geometry/Place Bound Top")
		(29 "B.CrtYd" user "Package Geometry/Place Bound Bottom")
		(35 "F.Fab" user "Ref Des/Assembly Top")
		(33 "B.Fab" user "Ref Des/Assembly Bottom")
	)
	(footprint ""
		(layer "F.Cu")
		(at 113.24717 -78.5368)
		(property "Reference" "STP70"
			(at 0 0 0)
			(layer "F.SilkS")
			(hide yes)
			(effects
				(font
					(size 1.27 1.27)
				)
			)
		)
		(property "Value" "TPAD28"
			(at 0.0127 -1.8034 0)
			(unlocked yes)
			(layer "F.Fab")
			(hide yes)
			(effects
				(font
					(size 1.016 1.016)
					(thickness 0.1524)
				)
			)
		)
		(property "Device Type" "TPAD28"
			(at 0.0127 -3.3274 0)
			(unlocked yes)
			(layer "F.Fab")
			(hide yes)
			(effects
				(font
					(size 1.016 1.016)
					(thickness 0.1524)
				)
			)
		)
		(duplicate_pad_numbers_are_jumpers no)
		(fp_poly
			(pts
				(arc
					(start 0.3556 0)
					(mid -0.3556 0)
					(end 0.3556 0)
				)
			)
			(stroke
				(width 0)
				(type default)
			)
			(fill no)
			(layer "F.CrtYd")
		)
		(fp_poly
			(pts
				(arc
					(start 0.6096 0)
					(mid -0.6096 0)
					(end 0.6096 0)
				)
			)
			(stroke
				(width 0)
				(type default)
			)
			(fill no)
			(layer "F.Fab")
		)
		(pad "1" smd circle
			(at 0 0)
			(size 0.7112 0.7112)
			(layers "F.Cu" "F.Mask" "F.Paste")
			(net "EXP_TEST_MUX32")
		)
	)
	(footprint ""
		(layer "F.Cu")
		(at 101.74097 -114.3 180)
		(property "Reference" "SC1089"
			(at 0 0 180)
			(layer "F.SilkS")
			(hide yes)
			(effects
				(font
					(size 1.27 1.27)
				)
			)
		)
		(property "Value" "SCD01U10V1KX-GP"
			(at -2.8321 -1.7399 180)
			(unlocked yes)
			(layer "F.Fab")
			(hide yes)
			(effects
				(font
					(size 1.016 1.016)
					(thickness 0.1524)
				)
			)
		)
		(property "Device Type" "C0201H13"
			(at -2.8321 -3.2639 180)
			(unlocked yes)
			(layer "F.Fab")
			(hide yes)
			(effects
				(font
					(size 1.016 1.016)
					(thickness 0.1524)
				)
			)
		)
		(duplicate_pad_numbers_are_jumpers no)
		(fp_rect
			(start -0.2794 0.6477)
			(end 0.2794 -0.6477)
			(stroke
				(width 0)
				(type default)
			)
			(fill no)
			(layer "F.CrtYd")
		)
		(fp_rect
			(start -0.2794 0.6477)
			(end 0.2794 -0.6477)
			(stroke
				(width 0)
				(type default)
			)
			(fill no)
			(layer "F.Fab")
		)
		(pad "1" smd custom
			(at 0 -0.2794 180)
			(size 0.0762 0.0762)
			(layers "F.Cu" "F.Mask" "F.Paste")
			(net "SAS_HDD_TX11_N")
			(options
				(clearance outline)
				(anchor circle)
			)
			(primitives
				(gr_poly
					(pts
						(arc
							(start 0.1524 -0.127)
							(mid 0.137521 -0.162921)
							(end 0.1016 -0.1778)
						)
						(arc
							(start -0.1016 -0.1778)
							(mid -0.137521 -0.162921)
							(end -0.1524 -0.127)
						)
						(arc
							(start -0.1524 0.127)
							(mid -0.137521 0.162921)
							(end -0.1016 0.1778)
						)
						(arc
							(start 0.1016 0.1778)
							(mid 0.137521 0.162921)
							(end 0.1524 0.127)
						)
					)
					(width 0)
					(fill yes)
				)
			)
		)
		(pad "2" smd custom
			(at 0 0.2794 180)
			(size 0.0762 0.0762)
			(layers "F.Cu" "F.Mask" "F.Paste")
			(net "SAS_EXP_GF_TX_DN15")
			(options
				(clearance outline)
				(anchor circle)
			)
			(primitives
				(gr_poly
					(pts
						(arc
							(start 0.1524 -0.127)
							(mid 0.137521 -0.162921)
							(end 0.1016 -0.1778)
						)
						(arc
							(start -0.1016 -0.1778)
							(mid -0.137521 -0.162921)
							(end -0.1524 -0.127)
						)
						(arc
							(start -0.1524 0.127)
							(mid -0.137521 0.162921)
							(end -0.1016 0.1778)
						)
						(arc
							(start 0.1016 0.1778)
							(mid 0.137521 0.162921)
							(end 0.1524 0.127)
						)
					)
					(width 0)
					(fill yes)
				)
			)
		)
	)
	(footprint ""
		(layer "F.Cu")
		(at 95.89897 -81.661 -90)
		(property "Reference" "SR789"
			(at 0 0 270)
			(layer "F.SilkS")
			(hide yes)
			(effects
				(font
					(size 1.27 1.27)
				)
			)
		)
		(property "Value" "4K75R2F-1-GP"
			(at 0.064008 -3.993896 270)
			(unlocked yes)
			(layer "F.Fab")
			(hide yes)
			(effects
				(font
					(size 1.016 1.016)
					(thickness 0.1524)
				)
			)
		)
		(property "Device Type" "R402H16"
			(at 0.064008 -5.517896 270)
			(unlocked yes)
			(layer "F.Fab")
			(hide yes)
			(effects
				(font
					(size 1.016 1.016)
					(thickness 0.1524)
				)
			)
		)
		(duplicate_pad_numbers_are_jumpers no)
		(fp_line
			(start -0.508 -0.9398)
			(end -0.508 0.9398)
			(stroke
				(width 0.1524)
				(type default)
			)
			(layer "F.SilkS")
		)
		(fp_line
			(start 0.508 -0.9398)
			(end -0.508 -0.9398)
			(stroke
				(width 0.1524)
				(type default)
			)
			(layer "F.SilkS")
		)
		(fp_rect
			(start -0.508 0.9398)
			(end 0.508 -0.9398)
			(stroke
				(width 0)
				(type default)
			)
			(fill no)
			(layer "F.CrtYd")
		)
		(fp_rect
			(start -0.508 0.9398)
			(end 0.508 -0.9398)
			(stroke
				(width 0)
				(type default)
			)
			(fill no)
			(layer "F.Fab")
		)
		(pad "1" smd custom
			(at 0 -0.4445 270)
			(size 0.1397 0.1397)
			(layers "F.Cu" "F.Mask" "F.Paste")
			(net "EXP_CPU_MODE_1")
			(options
				(clearance outline)
				(anchor circle)
			)
			(primitives
				(gr_poly
					(pts
						(arc
							(start -0.1778 -0.2794)
							(mid -0.249642 -0.249642)
							(end -0.2794 -0.1778)
						)
						(arc
							(start -0.2794 0.1778)
							(mid -0.249642 0.249642)
							(end -0.1778 0.2794)
						)
						(arc
							(start 0.1778 0.2794)
							(mid 0.249642 0.249642)
							(end 0.2794 0.1778)
						)
						(arc
							(start 0.2794 -0.1778)
							(mid 0.249642 -0.249642)
							(end 0.1778 -0.2794)
						)
					)
					(width 0)
					(fill yes)
				)
			)
		)
		(pad "2" smd custom
			(at 0 0.4445 270)
			(size 0.1397 0.1397)
			(layers "F.Cu" "F.Mask" "F.Paste")
			(net "GND")
			(options
				(clearance outline)
				(anchor circle)
			)
			(primitives
				(gr_poly
					(pts
						(arc
							(start -0.1778 -0.2794)
							(mid -0.249642 -0.249642)
							(end -0.2794 -0.1778)
						)
						(arc
							(start -0.2794 0.1778)
							(mid -0.249642 0.249642)
							(end -0.1778 0.2794)
						)
						(arc
							(start 0.1778 0.2794)
							(mid 0.249642 0.249642)
							(end 0.2794 0.1778)
						)
						(arc
							(start 0.2794 -0.1778)
							(mid 0.249642 -0.249642)
							(end 0.1778 -0.2794)
						)
					)
					(width 0)
					(fill yes)
				)
			)
		)
	)
	(footprint ""
		(layer "F.Cu")
		(at 14.428216 -211.00288 -90)
		(property "Reference" "SR589"
			(at 0 0 270)
			(layer "F.SilkS")
			(hide yes)
			(effects
				(font
					(size 1.27 1.27)
				)
			)
		)
		(property "Value" "4K7R2F-GP"
			(at 0.064008 -3.993896 270)
			(unlocked yes)
			(layer "F.Fab")
			(hide yes)
			(effects
				(font
					(size 1.016 1.016)
					(thickness 0.1524)
				)
			)
		)
		(property "Device Type" "R402H16"
			(at 0.064008 -5.517896 270)
			(unlocked yes)
			(layer "F.Fab")
			(hide yes)
			(effects
				(font
					(size 1.016 1.016)
					(thickness 0.1524)
				)
			)
		)
		(duplicate_pad_numbers_are_jumpers no)
		(fp_line
			(start -0.508 -0.9398)
			(end -0.508 0.9398)
			(stroke
				(width 0.1524)
				(type default)
			)
			(layer "F.SilkS")
		)
		(fp_line
			(start 0.508 -0.9398)
			(end -0.508 -0.9398)
			(stroke
				(width 0.1524)
				(type default)
			)
			(layer "F.SilkS")
		)
		(fp_rect
			(start -0.508 0.9398)
			(end 0.508 -0.9398)
			(stroke
				(width 0)
				(type default)
			)
			(fill no)
			(layer "F.CrtYd")
		)
		(fp_rect
			(start -0.508 0.9398)
			(end 0.508 -0.9398)
			(stroke
				(width 0)
				(type default)
			)
			(fill no)
			(layer "F.Fab")
		)
		(pad "1" smd custom
			(at 0 -0.4445 270)
			(size 0.1397 0.1397)
			(layers "F.Cu" "F.Mask" "F.Paste")
			(net "BMC_IOEXP_SDA_10")
			(options
				(clearance outline)
				(anchor circle)
			)
			(primitives
				(gr_poly
					(pts
						(arc
							(start -0.1778 -0.2794)
							(mid -0.249642 -0.249642)
							(end -0.2794 -0.1778)
						)
						(arc
							(start -0.2794 0.1778)
							(mid -0.249642 0.249642)
							(end -0.1778 0.2794)
						)
						(arc
							(start 0.1778 0.2794)
							(mid 0.249642 0.249642)
							(end 0.2794 0.1778)
						)
						(arc
							(start 0.2794 -0.1778)
							(mid 0.249642 -0.249642)
							(end 0.1778 -0.2794)
						)
					)
					(width 0)
					(fill yes)
				)
			)
		)
		(pad "2" smd custom
			(at 0 0.4445 270)
			(size 0.1397 0.1397)
			(layers "F.Cu" "F.Mask" "F.Paste")
			(net "P1V8_E")
			(options
				(clearance outline)
				(anchor circle)
			)
			(primitives
				(gr_poly
					(pts
						(arc
							(start -0.1778 -0.2794)
							(mid -0.249642 -0.249642)
							(end -0.2794 -0.1778)
						)
						(arc
							(start -0.2794 0.1778)
							(mid -0.249642 0.249642)
							(end -0.1778 0.2794)
						)
						(arc
							(start 0.1778 0.2794)
							(mid 0.249642 0.249642)
							(end 0.2794 0.1778)
						)
						(arc
							(start 0.2794 -0.1778)
							(mid 0.249642 -0.249642)
							(end 0.1778 -0.2794)
						)
					)
					(width 0)
					(fill yes)
				)
			)
		)
	)
	(footprint ""
		(layer "F.Cu")
		(at 299.72 -191.897)
		(property "Reference" "R583"
			(at 0 0 0)
			(layer "F.SilkS")
			(hide yes)
			(effects
				(font
					(size 1.27 1.27)
				)
			)
		)
		(property "Value" "0R2J-2-GP"
			(at 0.064008 -3.993896 0)
			(unlocked yes)
			(layer "F.Fab")
			(hide yes)
			(effects
				(font
					(size 1.016 1.016)
					(thickness 0.1524)
				)
			)
		)
		(property "Device Type" "R402H16"
			(at 0.064008 -5.517896 0)
			(unlocked yes)
			(layer "F.Fab")
			(hide yes)
			(effects
				(font
					(size 1.016 1.016)
					(thickness 0.1524)
				)
			)
		)
		(duplicate_pad_numbers_are_jumpers no)
		(fp_line
			(start -0.508 -0.9398)
			(end -0.508 0.9398)
			(stroke
				(width 0.1524)
				(type default)
			)
			(layer "F.SilkS")
		)
		(fp_line
			(start 0.508 -0.9398)
			(end -0.508 -0.9398)
			(stroke
				(width 0.1524)
				(type default)
			)
			(layer "F.SilkS")
		)
		(fp_rect
			(start -0.508 0.9398)
			(end 0.508 -0.9398)
			(stroke
				(width 0)
				(type default)
			)
			(fill no)
			(layer "F.CrtYd")
		)
		(fp_rect
			(start -0.508 0.9398)
			(end 0.508 -0.9398)
			(stroke
				(width 0)
				(type default)
			)
			(fill no)
			(layer "F.Fab")
		)
		(pad "1" smd custom
			(at 0 -0.4445)
			(size 0.1397 0.1397)
			(layers "F.Cu" "F.Mask" "F.Paste")
			(net "BMC_UART_SWITCH_2")
			(options
				(clearance outline)
				(anchor circle)
			)
			(primitives
				(gr_poly
					(pts
						(arc
							(start -0.1778 -0.2794)
							(mid -0.249642 -0.249642)
							(end -0.2794 -0.1778)
						)
						(arc
							(start -0.2794 0.1778)
							(mid -0.249642 0.249642)
							(end -0.1778 0.2794)
						)
						(arc
							(start 0.1778 0.2794)
							(mid 0.249642 0.249642)
							(end 0.2794 0.1778)
						)
						(arc
							(start 0.2794 -0.1778)
							(mid 0.249642 -0.249642)
							(end 0.1778 -0.2794)
						)
					)
					(width 0)
					(fill yes)
				)
			)
		)
		(pad "2" smd custom
			(at 0 0.4445)
			(size 0.1397 0.1397)
			(layers "F.Cu" "F.Mask" "F.Paste")
			(net "BMC0_TACH12")
			(options
				(clearance outline)
				(anchor circle)
			)
			(primitives
				(gr_poly
					(pts
						(arc
							(start -0.1778 -0.2794)
							(mid -0.249642 -0.249642)
							(end -0.2794 -0.1778)
						)
						(arc
							(start -0.2794 0.1778)
							(mid -0.249642 0.249642)
							(end -0.1778 0.2794)
						)
						(arc
							(start 0.1778 0.2794)
							(mid 0.249642 0.249642)
							(end 0.2794 0.1778)
						)
						(arc
							(start 0.2794 -0.1778)
							(mid 0.249642 -0.249642)
							(end 0.1778 -0.2794)
						)
					)
					(width 0)
					(fill yes)
				)
			)
		)
	)
	(footprint ""
		(layer "F.Cu")
		(at 183.8198 -53.086 90)
		(property "Reference" "R22"
			(at 0 0 90)
			(layer "F.SilkS")
			(hide yes)
			(effects
				(font
					(size 1.27 1.27)
				)
			)
		)
		(property "Value" "10KR2F-2-GP"
			(at 0.064008 -3.993896 90)
			(unlocked yes)
			(layer "F.Fab")
			(hide yes)
			(effects
				(font
					(size 1.016 1.016)
					(thickness 0.1524)
				)
			)
		)
		(property "Device Type" "R402H16"
			(at 0.064008 -5.517896 90)
			(unlocked yes)
			(layer "F.Fab")
			(hide yes)
			(effects
				(font
					(size 1.016 1.016)
					(thickness 0.1524)
				)
			)
		)
		(duplicate_pad_numbers_are_jumpers no)
		(fp_line
			(start 0.508 -0.9398)
			(end -0.508 -0.9398)
			(stroke
				(width 0.1524)
				(type default)
			)
			(layer "F.SilkS")
		)
		(fp_line
			(start -0.508 -0.9398)
			(end -0.508 0.9398)
			(stroke
				(width 0.1524)
				(type default)
			)
			(layer "F.SilkS")
		)
		(fp_rect
			(start -0.508 0.9398)
			(end 0.508 -0.9398)
			(stroke
				(width 0)
				(type default)
			)
			(fill no)
			(layer "F.CrtYd")
		)
		(fp_rect
			(start -0.508 0.9398)
			(end 0.508 -0.9398)
			(stroke
				(width 0)
				(type default)
			)
			(fill no)
			(layer "F.Fab")
		)
		(pad "1" smd custom
			(at 0 -0.4445 90)
			(size 0.1397 0.1397)
			(layers "F.Cu" "F.Mask" "F.Paste")
			(net "P0V9_E_PG")
			(options
				(clearance outline)
				(anchor circle)
			)
			(primitives
				(gr_poly
					(pts
						(arc
							(start -0.1778 -0.2794)
							(mid -0.249642 -0.249642)
							(end -0.2794 -0.1778)
						)
						(arc
							(start -0.2794 0.1778)
							(mid -0.249642 0.249642)
							(end -0.1778 0.2794)
						)
						(arc
							(start 0.1778 0.2794)
							(mid 0.249642 0.249642)
							(end 0.2794 0.1778)
						)
						(arc
							(start 0.2794 -0.1778)
							(mid 0.249642 -0.249642)
							(end 0.1778 -0.2794)
						)
					)
					(width 0)
					(fill yes)
				)
			)
		)
		(pad "2" smd custom
			(at 0 0.4445 90)
			(size 0.1397 0.1397)
			(layers "F.Cu" "F.Mask" "F.Paste")
			(net "MSB_PRSNT_AND_3")
			(options
				(clearance outline)
				(anchor circle)
			)
			(primitives
				(gr_poly
					(pts
						(arc
							(start -0.1778 -0.2794)
							(mid -0.249642 -0.249642)
							(end -0.2794 -0.1778)
						)
						(arc
							(start -0.2794 0.1778)
							(mid -0.249642 0.249642)
							(end -0.1778 0.2794)
						)
						(arc
							(start 0.1778 0.2794)
							(mid 0.249642 0.249642)
							(end 0.2794 0.1778)
						)
						(arc
							(start 0.2794 -0.1778)
							(mid 0.249642 -0.249642)
							(end 0.1778 -0.2794)
						)
					)
					(width 0)
					(fill yes)
				)
			)
		)
	)
	(footprint ""
		(layer "F.Cu")
		(at 253.746 -136.779)
		(property "Reference" "R7906"
			(at 0 0 0)
			(layer "F.SilkS")
			(hide yes)
			(effects
				(font
					(size 1.27 1.27)
				)
			)
		)
		(property "Value" "0R2J-2-GP"
			(at 0.064008 -3.993896 0)
			(unlocked yes)
			(layer "F.Fab")
			(hide yes)
			(effects
				(font
					(size 1.016 1.016)
					(thickness 0.1524)
				)
			)
		)
		(property "Device Type" "R402H16"
			(at 0.064008 -5.517896 0)
			(unlocked yes)
			(layer "F.Fab")
			(hide yes)
			(effects
				(font
					(size 1.016 1.016)
					(thickness 0.1524)
				)
			)
		)
		(duplicate_pad_numbers_are_jumpers no)
		(fp_line
			(start -0.508 -0.9398)
			(end -0.508 0.9398)
			(stroke
				(width 0.1524)
				(type default)
			)
			(layer "F.SilkS")
		)
		(fp_line
			(start 0.508 -0.9398)
			(end -0.508 -0.9398)
			(stroke
				(width 0.1524)
				(type default)
			)
			(layer "F.SilkS")
		)
		(fp_rect
			(start -0.508 0.9398)
			(end 0.508 -0.9398)
			(stroke
				(width 0)
				(type default)
			)
			(fill no)
			(layer "F.CrtYd")
		)
		(fp_rect
			(start -0.508 0.9398)
			(end 0.508 -0.9398)
			(stroke
				(width 0)
				(type default)
			)
			(fill no)
			(layer "F.Fab")
		)
		(pad "1" smd custom
			(at 0 -0.4445)
			(size 0.1397 0.1397)
			(layers "F.Cu" "F.Mask" "F.Paste")
			(net "CPU_BMC_UART_RX")
			(options
				(clearance outline)
				(anchor circle)
			)
			(primitives
				(gr_poly
					(pts
						(arc
							(start -0.1778 -0.2794)
							(mid -0.249642 -0.249642)
							(end -0.2794 -0.1778)
						)
						(arc
							(start -0.2794 0.1778)
							(mid -0.249642 0.249642)
							(end -0.1778 0.2794)
						)
						(arc
							(start 0.1778 0.2794)
							(mid 0.249642 0.249642)
							(end 0.2794 0.1778)
						)
						(arc
							(start 0.2794 -0.1778)
							(mid 0.249642 -0.249642)
							(end 0.1778 -0.2794)
						)
					)
					(width 0)
					(fill yes)
				)
			)
		)
		(pad "2" smd custom
			(at 0 0.4445)
			(size 0.1397 0.1397)
			(layers "F.Cu" "F.Mask" "F.Paste")
			(net "CPU_U193_PIN6_RX")
			(options
				(clearance outline)
				(anchor circle)
			)
			(primitives
				(gr_poly
					(pts
						(arc
							(start -0.1778 -0.2794)
							(mid -0.249642 -0.249642)
							(end -0.2794 -0.1778)
						)
						(arc
							(start -0.2794 0.1778)
							(mid -0.249642 0.249642)
							(end -0.1778 0.2794)
						)
						(arc
							(start 0.1778 0.2794)
							(mid 0.249642 0.249642)
							(end 0.2794 0.1778)
						)
						(arc
							(start 0.2794 -0.1778)
							(mid 0.249642 -0.249642)
							(end 0.1778 -0.2794)
						)
					)
					(width 0)
					(fill yes)
				)
			)
		)
	)
	(footprint ""
		(layer "F.Cu")
		(at 199.517 -220.472)
		(property "Reference" "U174"
			(at 0 0 0)
			(layer "F.SilkS")
			(hide yes)
			(effects
				(font
					(size 1.27 1.27)
				)
			)
		)
		(property "Value" "SNLVC1G126DCKR-GP"
			(at -2.3368 -8.6868 0)
			(unlocked yes)
			(layer "F.Fab")
			(hide yes)
			(effects
				(font
					(size 1.016 1.016)
					(thickness 0.1524)
				)
			)
		)
		(property "Device Type" "SC70-5H44"
			(at -2.3114 -10.414 0)
			(unlocked yes)
			(layer "F.Fab")
			(hide yes)
			(effects
				(font
					(size 1.016 1.016)
					(thickness 0.1524)
				)
			)
		)
		(duplicate_pad_numbers_are_jumpers no)
		(fp_line
			(start -1.27 -1.7018)
			(end 1.27 -1.7018)
			(stroke
				(width 0.1524)
				(type default)
			)
			(layer "F.SilkS")
		)
		(fp_line
			(start -1.27 1.7018)
			(end -1.27 -1.7018)
			(stroke
				(width 0.1524)
				(type default)
			)
			(layer "F.SilkS")
		)
		(fp_line
			(start 0.6604 -1.8034)
			(end 1.3843 -1.8034)
			(stroke
				(width 0.3302)
				(type default)
			)
			(layer "F.SilkS")
		)
		(fp_line
			(start 1.27 -1.7018)
			(end 1.27 1.7018)
			(stroke
				(width 0.1524)
				(type default)
			)
			(layer "F.SilkS")
		)
		(fp_line
			(start 1.27 1.7018)
			(end -1.27 1.7018)
			(stroke
				(width 0.1524)
				(type default)
			)
			(layer "F.SilkS")
		)
		(fp_line
			(start 1.3843 -1.8034)
			(end 1.3843 -1.1176)
			(stroke
				(width 0.3302)
				(type default)
			)
			(layer "F.SilkS")
		)
		(fp_rect
			(start -1.524 1.9558)
			(end 1.524 -1.9558)
			(stroke
				(width 0)
				(type default)
			)
			(fill no)
			(layer "F.CrtYd")
		)
		(fp_poly
			(pts
				(xy -1.524 -1.9558) (xy 1.524 -1.9558) (xy 1.524 1.9558) (xy -1.524 1.9558)
			)
			(stroke
				(width 0)
				(type default)
			)
			(fill no)
			(layer "F.Fab")
		)
		(pad "1" smd rect
			(at 0.65024 -0.8255)
			(size 0.4064 1.2192)
			(layers "F.Cu" "F.Mask" "F.Paste")
			(net "FM_BMC_READY_N")
		)
		(pad "2" smd rect
			(at 0 -0.8255)
			(size 0.4064 1.2192)
			(layers "F.Cu" "F.Mask" "F.Paste")
			(net "RSTBTN_FP_N")
		)
		(pad "3" smd rect
			(at -0.65024 -0.8255)
			(size 0.4064 1.2192)
			(layers "F.Cu" "F.Mask" "F.Paste")
			(net "GND")
		)
		(pad "4" smd rect
			(at -0.65024 0.8255)
			(size 0.4064 1.2192)
			(layers "F.Cu" "F.Mask" "F.Paste")
			(net "RSTBTN_OUT_N")
		)
		(pad "5" smd rect
			(at 0.65024 0.8255)
			(size 0.4064 1.2192)
			(layers "F.Cu" "F.Mask" "F.Paste")
			(net "P3V3_STBY")
		)
	)
)
